(kicad_pcb
	(version 20260206)
	(generator "pcbnew")
	(generator_version "10.0")
	(general
		(thickness 1.6)
		(legacy_teardrops no)
	)
	(paper "A4")
	(title_block
		(title "9052_F0T_PDB_Converter_Brick_F_V03_1208_1600_OCP.brd")
		(comment 1 "Grand Teton / footprints 141-147 of 578")
	)
	(layers
		(0 "F.Cu" signal "TOP")
		(4 "In1.Cu" signal "GND")
		(6 "In2.Cu" signal "IN1")
		(8 "In3.Cu" signal "GND1")
		(10 "In4.Cu" signal "VCC")
		(12 "In5.Cu" signal "VCC1")
		(14 "In6.Cu" signal "GND2")
		(16 "In7.Cu" signal "IN2")
		(18 "In8.Cu" signal "GND3")
		(2 "B.Cu" signal "BOTTOM")
		(9 "F.Adhes" user "F.Adhesive")
		(11 "B.Adhes" user "B.Adhesive")
		(13 "F.Paste" user "Package Geometry/Pastemask Top")
		(15 "B.Paste" user "Package Geometry/Pastemask Bottom")
		(5 "F.SilkS" user "Ref Des/Silkscreen Top")
		(7 "B.SilkS" user "Ref Des/Silkscreen Bottom")
		(1 "F.Mask" user "Board Geometry/Soldermask Top")
		(3 "B.Mask" user "Board Geometry/Soldermask Bottom")
		(17 "Dwgs.User" user "User.Drawings")
		(19 "Cmts.User" user "User.Comments")
		(21 "Eco1.User" user "User.Eco1")
		(23 "Eco2.User" user "User.Eco2")
		(25 "Edge.Cuts" user "Board Geometry/Outline")
		(27 "Margin" user)
		(31 "F.CrtYd" user "Package Geometry/Place Bound Top")
		(29 "B.CrtYd" user "Package Geometry/Place Bound Bottom")
		(35 "F.Fab" user "Ref Des/Assembly Top")
		(33 "B.Fab" user "Ref Des/Assembly Bottom")
	)
	(footprint ""
		(layer "F.Cu")
		(at 45.67936 -61.55182)
		(property "Reference" "R5900"
			(at 0 0 0)
			(layer "F.SilkS")
			(hide yes)
			(effects
				(font
					(size 1.27 1.27)
				)
			)
		)
		(property "Value" ""
			(at 0 0 0)
			(layer "F.Fab")
			(effects
				(font
					(size 1.27 1.27)
				)
			)
		)
		(duplicate_pad_numbers_are_jumpers no)
		(fp_line
			(start -0.7874 -0.4064)
			(end 0.7874 -0.4064)
			(stroke
				(width 0.1524)
				(type default)
			)
			(layer "F.SilkS")
		)
		(fp_line
			(start -0.7874 0.4064)
			(end -0.7874 -0.4064)
			(stroke
				(width 0.1524)
				(type default)
			)
			(layer "F.SilkS")
		)
		(fp_line
			(start 0.7874 -0.4064)
			(end 0.7874 0.4064)
			(stroke
				(width 0.1524)
				(type default)
			)
			(layer "F.SilkS")
		)
		(fp_line
			(start 0.7874 0.4064)
			(end -0.7874 0.4064)
			(stroke
				(width 0.1524)
				(type default)
			)
			(layer "F.SilkS")
		)
		(fp_line
			(start -0.67945 -0.305054)
			(end -0.12065 -0.305054)
			(stroke
				(width 0.1)
				(type default)
			)
			(layer "F.Fab")
		)
		(fp_line
			(start -0.67945 0.3048)
			(end -0.67945 -0.305054)
			(stroke
				(width 0.1)
				(type default)
			)
			(layer "F.Fab")
		)
		(fp_line
			(start -0.12065 -0.305054)
			(end -0.12065 -0.2794)
			(stroke
				(width 0.1)
				(type default)
			)
			(layer "F.Fab")
		)
		(fp_line
			(start -0.12065 -0.2794)
			(end 0.12065 -0.2794)
			(stroke
				(width 0.1)
				(type default)
			)
			(layer "F.Fab")
		)
		(fp_line
			(start -0.12065 0.2794)
			(end -0.12065 0.3048)
			(stroke
				(width 0.1)
				(type default)
			)
			(layer "F.Fab")
		)
		(fp_line
			(start -0.12065 0.3048)
			(end -0.67945 0.3048)
			(stroke
				(width 0.1)
				(type default)
			)
			(layer "F.Fab")
		)
		(fp_line
			(start 0.120396 0.2794)
			(end -0.12065 0.2794)
			(stroke
				(width 0.1)
				(type default)
			)
			(layer "F.Fab")
		)
		(fp_line
			(start 0.120396 0.3048)
			(end 0.120396 0.2794)
			(stroke
				(width 0.1)
				(type default)
			)
			(layer "F.Fab")
		)
		(fp_line
			(start 0.12065 -0.3048)
			(end 0.67945 -0.3048)
			(stroke
				(width 0.1)
				(type default)
			)
			(layer "F.Fab")
		)
		(fp_line
			(start 0.12065 -0.2794)
			(end 0.12065 -0.3048)
			(stroke
				(width 0.1)
				(type default)
			)
			(layer "F.Fab")
		)
		(fp_line
			(start 0.67945 -0.3048)
			(end 0.67945 0.3048)
			(stroke
				(width 0.1)
				(type default)
			)
			(layer "F.Fab")
		)
		(fp_line
			(start 0.67945 0.3048)
			(end 0.120396 0.3048)
			(stroke
				(width 0.1)
				(type default)
			)
			(layer "F.Fab")
		)
		(pad "1" smd circle
			(at -0.40005 0)
			(size 0 0)
			(layers "F.Cu" "F.Mask" "F.Paste")
			(net "P12V_HPDB_0_IMON")
		)
		(pad "2" smd circle
			(at 0.40005 0)
			(size 0 0)
			(layers "F.Cu" "F.Mask" "F.Paste")
			(net "GND")
		)
	)
	(footprint ""
		(layer "F.Cu")
		(at 60.452 -60.198)
		(property "Reference" "PR86"
			(at 0 0 0)
			(layer "F.SilkS")
			(hide yes)
			(effects
				(font
					(size 1.27 1.27)
				)
			)
		)
		(property "Value" ""
			(at 0 0 0)
			(layer "F.Fab")
			(effects
				(font
					(size 1.27 1.27)
				)
			)
		)
		(duplicate_pad_numbers_are_jumpers no)
		(fp_line
			(start -1.651 -0.8382)
			(end 1.651 -0.8382)
			(stroke
				(width 0.1524)
				(type default)
			)
			(layer "F.SilkS")
		)
		(fp_line
			(start -1.651 0.8382)
			(end -1.651 -0.8382)
			(stroke
				(width 0.1524)
				(type default)
			)
			(layer "F.SilkS")
		)
		(fp_line
			(start 1.651 -0.8382)
			(end 1.651 0.8382)
			(stroke
				(width 0.1524)
				(type default)
			)
			(layer "F.SilkS")
		)
		(fp_line
			(start 1.651 0.8382)
			(end -1.651 0.8382)
			(stroke
				(width 0.1524)
				(type default)
			)
			(layer "F.SilkS")
		)
		(fp_line
			(start -1.559814 -0.7366)
			(end -1.559814 0.7366)
			(stroke
				(width 0.1)
				(type default)
			)
			(layer "F.Fab")
		)
		(fp_line
			(start -1.559814 0.7366)
			(end -1.524 0.7366)
			(stroke
				(width 0.1)
				(type default)
			)
			(layer "F.Fab")
		)
		(fp_line
			(start -1.524 -0.7366)
			(end -1.559814 -0.7366)
			(stroke
				(width 0.1)
				(type default)
			)
			(layer "F.Fab")
		)
		(fp_line
			(start -1.524 0.7366)
			(end 1.524 0.7366)
			(stroke
				(width 0.1)
				(type default)
			)
			(layer "F.Fab")
		)
		(fp_line
			(start 1.524 -0.7366)
			(end -1.524 -0.7366)
			(stroke
				(width 0.1)
				(type default)
			)
			(layer "F.Fab")
		)
		(fp_line
			(start 1.524 0.7366)
			(end 1.560576 0.7366)
			(stroke
				(width 0.1)
				(type default)
			)
			(layer "F.Fab")
		)
		(fp_line
			(start 1.560576 -0.7366)
			(end 1.524 -0.7366)
			(stroke
				(width 0.1)
				(type default)
			)
			(layer "F.Fab")
		)
		(fp_line
			(start 1.560576 0.7366)
			(end 1.560576 -0.7366)
			(stroke
				(width 0.1)
				(type default)
			)
			(layer "F.Fab")
		)
		(pad "1" smd rect
			(at -0.94996 0 180)
			(size 1.1176 1.3716)
			(layers "F.Cu" "F.Mask" "F.Paste")
			(net "P12V_BRICK")
		)
		(pad "2" smd rect
			(at 0.94996 0 180)
			(size 1.1176 1.3716)
			(layers "F.Cu" "F.Mask" "F.Paste")
			(net "GND")
		)
	)
	(footprint ""
		(layer "F.Cu")
		(at 315.000132 -14.59992 -90)
		(property "Reference" "H20"
			(at 0.92329 -6.246368 0)
			(unlocked yes)
			(layer "F.SilkS")
			(effects
				(font
					(size 0.7874 0.5842)
					(thickness 0.1524)
				)
				(justify left)
			)
		)
		(property "Value" ""
			(at 0 0 270)
			(layer "F.Fab")
			(effects
				(font
					(size 1.27 1.27)
				)
			)
		)
		(duplicate_pad_numbers_are_jumpers no)
		(pad "1" thru_hole circle
			(at 0 0 270)
			(size 10.16 10.16)
			(drill 6.4008
				(offset 0 0)
			)
			(layers "*.Cu" "*.Mask")
			(remove_unused_layers no)
			(net "GND")
			(clearance -1.6256)
			(padstack
				(mode front_inner_back)
				(layer "Inner"
					(shape circle)
					(size 10.16 10.16)
					(clearance -1.6256)
				)
				(layer "B.Cu"
					(shape oval)
					(size 10.0076 32.004)
					(offset 0 10.9982)
					(clearance -1.5494)
				)
			)
		)
	)
	(footprint ""
		(layer "F.Cu")
		(at 191.643 -17.399)
		(property "Reference" "PC112"
			(at 0 0 0)
			(layer "F.SilkS")
			(hide yes)
			(effects
				(font
					(size 1.27 1.27)
				)
			)
		)
		(property "Value" ""
			(at 0 0 0)
			(layer "F.Fab")
			(effects
				(font
					(size 1.27 1.27)
				)
			)
		)
		(duplicate_pad_numbers_are_jumpers no)
		(fp_line
			(start -0.7874 -0.4064)
			(end 0.7874 -0.4064)
			(stroke
				(width 0.1524)
				(type default)
			)
			(layer "F.SilkS")
		)
		(fp_line
			(start -0.7874 0.4064)
			(end -0.7874 -0.4064)
			(stroke
				(width 0.1524)
				(type default)
			)
			(layer "F.SilkS")
		)
		(fp_line
			(start 0.7874 -0.4064)
			(end 0.7874 0.4064)
			(stroke
				(width 0.1524)
				(type default)
			)
			(layer "F.SilkS")
		)
		(fp_line
			(start 0.7874 0.4064)
			(end -0.7874 0.4064)
			(stroke
				(width 0.1524)
				(type default)
			)
			(layer "F.SilkS")
		)
		(fp_line
			(start -0.67945 -0.305054)
			(end -0.12065 -0.305054)
			(stroke
				(width 0.1)
				(type default)
			)
			(layer "F.Fab")
		)
		(fp_line
			(start -0.67945 0.3048)
			(end -0.67945 -0.305054)
			(stroke
				(width 0.1)
				(type default)
			)
			(layer "F.Fab")
		)
		(fp_line
			(start -0.12065 -0.305054)
			(end -0.12065 -0.2794)
			(stroke
				(width 0.1)
				(type default)
			)
			(layer "F.Fab")
		)
		(fp_line
			(start -0.12065 -0.2794)
			(end 0.12065 -0.2794)
			(stroke
				(width 0.1)
				(type default)
			)
			(layer "F.Fab")
		)
		(fp_line
			(start -0.12065 0.2794)
			(end -0.12065 0.3048)
			(stroke
				(width 0.1)
				(type default)
			)
			(layer "F.Fab")
		)
		(fp_line
			(start -0.12065 0.3048)
			(end -0.67945 0.3048)
			(stroke
				(width 0.1)
				(type default)
			)
			(layer "F.Fab")
		)
		(fp_line
			(start 0.120396 0.2794)
			(end -0.12065 0.2794)
			(stroke
				(width 0.1)
				(type default)
			)
			(layer "F.Fab")
		)
		(fp_line
			(start 0.120396 0.3048)
			(end 0.120396 0.2794)
			(stroke
				(width 0.1)
				(type default)
			)
			(layer "F.Fab")
		)
		(fp_line
			(start 0.12065 -0.3048)
			(end 0.67945 -0.3048)
			(stroke
				(width 0.1)
				(type default)
			)
			(layer "F.Fab")
		)
		(fp_line
			(start 0.12065 -0.2794)
			(end 0.12065 -0.3048)
			(stroke
				(width 0.1)
				(type default)
			)
			(layer "F.Fab")
		)
		(fp_line
			(start 0.67945 -0.3048)
			(end 0.67945 0.3048)
			(stroke
				(width 0.1)
				(type default)
			)
			(layer "F.Fab")
		)
		(fp_line
			(start 0.67945 0.3048)
			(end 0.120396 0.3048)
			(stroke
				(width 0.1)
				(type default)
			)
			(layer "F.Fab")
		)
		(pad "1" smd circle
			(at -0.40005 0)
			(size 0 0)
			(layers "F.Cu" "F.Mask" "F.Paste")
			(net "P3V3_AUX")
		)
		(pad "2" smd circle
			(at 0.40005 0)
			(size 0 0)
			(layers "F.Cu" "F.Mask" "F.Paste")
			(net "GND")
		)
	)
	(footprint ""
		(layer "F.Cu")
		(at 297.538394 -83.5025 180)
		(property "Reference" "PR6959"
			(at 0 0 180)
			(layer "F.SilkS")
			(hide yes)
			(effects
				(font
					(size 1.27 1.27)
				)
			)
		)
		(property "Value" ""
			(at 0 0 180)
			(layer "F.Fab")
			(effects
				(font
					(size 1.27 1.27)
				)
			)
		)
		(duplicate_pad_numbers_are_jumpers no)
		(fp_line
			(start 1.2954 0.5842)
			(end -1.2954 0.5842)
			(stroke
				(width 0.1524)
				(type default)
			)
			(layer "F.SilkS")
		)
		(fp_line
			(start 1.2954 -0.5842)
			(end 1.2954 0.5842)
			(stroke
				(width 0.1524)
				(type default)
			)
			(layer "F.SilkS")
		)
		(fp_line
			(start -1.2954 0.5842)
			(end -1.2954 -0.5842)
			(stroke
				(width 0.1524)
				(type default)
			)
			(layer "F.SilkS")
		)
		(fp_line
			(start -1.2954 -0.5842)
			(end 1.2954 -0.5842)
			(stroke
				(width 0.1524)
				(type default)
			)
			(layer "F.SilkS")
		)
		(fp_line
			(start 1.1938 0.4064)
			(end 0.8636 0.4064)
			(stroke
				(width 0.1)
				(type default)
			)
			(layer "F.Fab")
		)
		(fp_line
			(start 1.1938 -0.406654)
			(end 1.1938 0.4064)
			(stroke
				(width 0.1)
				(type default)
			)
			(layer "F.Fab")
		)
		(fp_line
			(start 0.8636 0.4572)
			(end -0.8636 0.4572)
			(stroke
				(width 0.1)
				(type default)
			)
			(layer "F.Fab")
		)
		(fp_line
			(start 0.8636 0.4064)
			(end 0.8636 0.4572)
			(stroke
				(width 0.1)
				(type default)
			)
			(layer "F.Fab")
		)
		(fp_line
			(start 0.8636 -0.406654)
			(end 1.1938 -0.406654)
			(stroke
				(width 0.1)
				(type default)
			)
			(layer "F.Fab")
		)
		(fp_line
			(start 0.8636 -0.4572)
			(end 0.8636 -0.406654)
			(stroke
				(width 0.1)
				(type default)
			)
			(layer "F.Fab")
		)
		(fp_line
			(start -0.8636 0.4572)
			(end -0.8636 0.4318)
			(stroke
				(width 0.1)
				(type default)
			)
			(layer "F.Fab")
		)
		(fp_line
			(start -0.8636 0.4318)
			(end -0.8636 0.4064)
			(stroke
				(width 0.1)
				(type default)
			)
			(layer "F.Fab")
		)
		(fp_line
			(start -0.8636 0.4064)
			(end -1.1938 0.4064)
			(stroke
				(width 0.1)
				(type default)
			)
			(layer "F.Fab")
		)
		(fp_line
			(start -0.8636 -0.406654)
			(end -0.8636 -0.4572)
			(stroke
				(width 0.1)
				(type default)
			)
			(layer "F.Fab")
		)
		(fp_line
			(start -0.8636 -0.4572)
			(end 0.8636 -0.4572)
			(stroke
				(width 0.1)
				(type default)
			)
			(layer "F.Fab")
		)
		(fp_line
			(start -1.1938 0.4064)
			(end -1.1938 -0.406654)
			(stroke
				(width 0.1)
				(type default)
			)
			(layer "F.Fab")
		)
		(fp_line
			(start -1.1938 -0.406654)
			(end -0.8636 -0.406654)
			(stroke
				(width 0.1)
				(type default)
			)
			(layer "F.Fab")
		)
		(pad "1" smd rect
			(at -0.7366 0 90)
			(size 0.7112 0.8128)
			(layers "F.Cu" "F.Mask" "F.Paste")
			(net "P52V_HS_1272_S_N")
		)
		(pad "2" smd rect
			(at 0.7366 0 90)
			(size 0.7112 0.8128)
			(layers "F.Cu" "F.Mask" "F.Paste")
			(net "P52V_HS1_SENSE_N_R2")
		)
	)
	(footprint ""
		(layer "F.Cu")
		(at 139.065 -62.992)
		(property "Reference" "PC28"
			(at 0 0 0)
			(layer "F.SilkS")
			(hide yes)
			(effects
				(font
					(size 1.27 1.27)
				)
			)
		)
		(property "Value" ""
			(at 0 0 0)
			(layer "F.Fab")
			(effects
				(font
					(size 1.27 1.27)
				)
			)
		)
		(duplicate_pad_numbers_are_jumpers no)
		(fp_line
			(start -0.7874 -0.4064)
			(end 0.7874 -0.4064)
			(stroke
				(width 0.1524)
				(type default)
			)
			(layer "F.SilkS")
		)
		(fp_line
			(start -0.7874 0.4064)
			(end -0.7874 -0.4064)
			(stroke
				(width 0.1524)
				(type default)
			)
			(layer "F.SilkS")
		)
		(fp_line
			(start 0.7874 -0.4064)
			(end 0.7874 0.4064)
			(stroke
				(width 0.1524)
				(type default)
			)
			(layer "F.SilkS")
		)
		(fp_line
			(start 0.7874 0.4064)
			(end -0.7874 0.4064)
			(stroke
				(width 0.1524)
				(type default)
			)
			(layer "F.SilkS")
		)
		(fp_line
			(start -0.6858 -0.3048)
			(end -0.1016 -0.3048)
			(stroke
				(width 0.1)
				(type default)
			)
			(layer "F.Fab")
		)
		(fp_line
			(start -0.6858 0.3048)
			(end -0.6858 -0.3048)
			(stroke
				(width 0.1)
				(type default)
			)
			(layer "F.Fab")
		)
		(fp_line
			(start -0.1016 -0.3048)
			(end -0.1016 -0.2794)
			(stroke
				(width 0.1)
				(type default)
			)
			(layer "F.Fab")
		)
		(fp_line
			(start -0.1016 -0.2794)
			(end 0.1016 -0.2794)
			(stroke
				(width 0.1)
				(type default)
			)
			(layer "F.Fab")
		)
		(fp_line
			(start -0.1016 0.2794)
			(end -0.1016 0.3048)
			(stroke
				(width 0.1)
				(type default)
			)
			(layer "F.Fab")
		)
		(fp_line
			(start -0.1016 0.3048)
			(end -0.6858 0.3048)
			(stroke
				(width 0.1)
				(type default)
			)
			(layer "F.Fab")
		)
		(fp_line
			(start 0.1016 -0.3048)
			(end 0.6858 -0.3048)
			(stroke
				(width 0.1)
				(type default)
			)
			(layer "F.Fab")
		)
		(fp_line
			(start 0.1016 -0.2794)
			(end 0.1016 -0.3048)
			(stroke
				(width 0.1)
				(type default)
			)
			(layer "F.Fab")
		)
		(fp_line
			(start 0.1016 0.2794)
			(end -0.1016 0.2794)
			(stroke
				(width 0.1)
				(type default)
			)
			(layer "F.Fab")
		)
		(fp_line
			(start 0.1016 0.3048)
			(end 0.1016 0.2794)
			(stroke
				(width 0.1)
				(type default)
			)
			(layer "F.Fab")
		)
		(fp_line
			(start 0.6858 -0.3048)
			(end 0.6858 0.3048)
			(stroke
				(width 0.1)
				(type default)
			)
			(layer "F.Fab")
		)
		(fp_line
			(start 0.6858 0.3048)
			(end 0.1016 0.3048)
			(stroke
				(width 0.1)
				(type default)
			)
			(layer "F.Fab")
		)
		(pad "1" smd rect
			(at -0.40005 0 180)
			(size 0.4572 0.508)
			(layers "F.Cu" "F.Mask" "F.Paste")
			(net "P12V_BRICK")
		)
		(pad "2" smd rect
			(at 0.40005 0 180)
			(size 0.4572 0.508)
			(layers "F.Cu" "F.Mask" "F.Paste")
			(net "GND")
		)
	)
	(footprint ""
		(layer "F.Cu")
		(at 259.334 -29.972 180)
		(property "Reference" "PR313"
			(at 0 0 180)
			(layer "F.SilkS")
			(hide yes)
			(effects
				(font
					(size 1.27 1.27)
				)
			)
		)
		(property "Value" ""
			(at 0 0 180)
			(layer "F.Fab")
			(effects
				(font
					(size 1.27 1.27)
				)
			)
		)
		(duplicate_pad_numbers_are_jumpers no)
		(fp_line
			(start 0.7874 0.4064)
			(end -0.7874 0.4064)
			(stroke
				(width 0.1524)
				(type default)
			)
			(layer "F.SilkS")
		)
		(fp_line
			(start 0.7874 -0.4064)
			(end 0.7874 0.4064)
			(stroke
				(width 0.1524)
				(type default)
			)
			(layer "F.SilkS")
		)
		(fp_line
			(start -0.7874 0.4064)
			(end -0.7874 -0.4064)
			(stroke
				(width 0.1524)
				(type default)
			)
			(layer "F.SilkS")
		)
		(fp_line
			(start -0.7874 -0.4064)
			(end 0.7874 -0.4064)
			(stroke
				(width 0.1524)
				(type default)
			)
			(layer "F.SilkS")
		)
		(fp_line
			(start 0.67945 0.3048)
			(end 0.120396 0.3048)
			(stroke
				(width 0.1)
				(type default)
			)
			(layer "F.Fab")
		)
		(fp_line
			(start 0.67945 -0.3048)
			(end 0.67945 0.3048)
			(stroke
				(width 0.1)
				(type default)
			)
			(layer "F.Fab")
		)
		(fp_line
			(start 0.12065 -0.2794)
			(end 0.12065 -0.3048)
			(stroke
				(width 0.1)
				(type default)
			)
			(layer "F.Fab")
		)
		(fp_line
			(start 0.12065 -0.3048)
			(end 0.67945 -0.3048)
			(stroke
				(width 0.1)
				(type default)
			)
			(layer "F.Fab")
		)
		(fp_line
			(start 0.120396 0.3048)
			(end 0.120396 0.2794)
			(stroke
				(width 0.1)
				(type default)
			)
			(layer "F.Fab")
		)
		(fp_line
			(start 0.120396 0.2794)
			(end -0.12065 0.2794)
			(stroke
				(width 0.1)
				(type default)
			)
			(layer "F.Fab")
		)
		(fp_line
			(start -0.12065 0.3048)
			(end -0.67945 0.3048)
			(stroke
				(width 0.1)
				(type default)
			)
			(layer "F.Fab")
		)
		(fp_line
			(start -0.12065 0.2794)
			(end -0.12065 0.3048)
			(stroke
				(width 0.1)
				(type default)
			)
			(layer "F.Fab")
		)
		(fp_line
			(start -0.12065 -0.2794)
			(end 0.12065 -0.2794)
			(stroke
				(width 0.1)
				(type default)
			)
			(layer "F.Fab")
		)
		(fp_line
			(start -0.12065 -0.305054)
			(end -0.12065 -0.2794)
			(stroke
				(width 0.1)
				(type default)
			)
			(layer "F.Fab")
		)
		(fp_line
			(start -0.67945 0.3048)
			(end -0.67945 -0.305054)
			(stroke
				(width 0.1)
				(type default)
			)
			(layer "F.Fab")
		)
		(fp_line
			(start -0.67945 -0.305054)
			(end -0.12065 -0.305054)
			(stroke
				(width 0.1)
				(type default)
			)
			(layer "F.Fab")
		)
		(pad "1" smd circle
			(at -0.40005 0 180)
			(size 0 0)
			(layers "F.Cu" "F.Mask" "F.Paste")
			(net "SMB_P52V_HSC_SCL")
		)
		(pad "2" smd circle
			(at 0.40005 0 180)
			(size 0 0)
			(layers "F.Cu" "F.Mask" "F.Paste")
			(net "SMB_P52V_VPDB_DEBUG_SCL")
		)
	)
)
